# S9S_MB_2U (Grand Teton) — schematic netlist excerpt (pin names and nets, part order shuffled) for the footprints in the layout excerpt that follows; sources: Cadence DE-HDL packaged netlist, KiCad conversion of 03242023_DA0F0TMBIJ0_F0T_Motherboard_J_brd_V01_OCP.brd

R4122  Q_RES  100K 1% EMPTY  pkg 0402LF  page 146 : A = PRSNT_CABLE_GPU_B3_N ; B = GND
PC641  Q_CAP  22UF 4V 20% X6S  pkg C0805  page 279 : A = PVCCD_HV_CPU0 ; B = GND
R4570  Q_RES  0 5% EMPTY  pkg 0402LF  page 145 : A = GPU_3V3IO_RSVD3 ; B = GPU_3V3IO_RSVD3_ISO

(kicad_pcb
	(version 20260206)
	(generator "pcbnew")
	(generator_version "10.0")
	(general
		(thickness 1.6)
		(legacy_teardrops no)
	)
	(paper "A4")
	(title_block
		(title "03242023_DA0F0TMBIJ0_F0T_Motherboard_J_brd_V01_OCP.brd")
		(comment 1 "Grand Teton / footprints 2813-2815 of 6105")
	)
	(layers
		(0 "F.Cu" signal "TOP")
		(4 "In1.Cu" signal "GND")
		(6 "In2.Cu" signal "IN1")
		(8 "In3.Cu" signal "GND1")
		(10 "In4.Cu" signal "IN2")
		(12 "In5.Cu" signal "GND2")
		(14 "In6.Cu" signal "IN3")
		(16 "In7.Cu" signal "GND3")
		(18 "In8.Cu" signal "VCC")
		(20 "In9.Cu" signal "VCC1")
		(22 "In10.Cu" signal "GND4")
		(24 "In11.Cu" signal "IN4")
		(26 "In12.Cu" signal "GND5")
		(28 "In13.Cu" signal "IN5")
		(30 "In14.Cu" signal "GND6")
		(32 "In15.Cu" signal "IN6")
		(34 "In16.Cu" signal "GND7")
		(2 "B.Cu" signal "BOTTOM")
		(9 "F.Adhes" user "F.Adhesive")
		(11 "B.Adhes" user "B.Adhesive")
		(13 "F.Paste" user "Package Geometry/Pastemask Top")
		(15 "B.Paste" user "Package Geometry/Pastemask Bottom")
		(5 "F.SilkS" user "Ref Des/Silkscreen Top")
		(7 "B.SilkS" user "Ref Des/Silkscreen Bottom")
		(1 "F.Mask" user "Board Geometry/Soldermask Top")
		(3 "B.Mask" user "Board Geometry/Soldermask Bottom")
		(17 "Dwgs.User" user "User.Drawings")
		(19 "Cmts.User" user "User.Comments")
		(21 "Eco1.User" user "User.Eco1")
		(23 "Eco2.User" user "User.Eco2")
		(25 "Edge.Cuts" user "Board Geometry/Outline")
		(27 "Margin" user)
		(31 "F.CrtYd" user "Package Geometry/Place Bound Top")
		(29 "B.CrtYd" user "Package Geometry/Place Bound Bottom")
		(35 "F.Fab" user "Ref Des/Assembly Top")
		(33 "B.Fab" user "Ref Des/Assembly Bottom")
	)
	(footprint ""
		(layer "F.Cu")
		(at 355.219 -390.439148 180)
		(property "Reference" "R4570"
			(at 0 0 180)
			(layer "F.SilkS")
			(hide yes)
			(effects
				(font
					(size 1.27 1.27)
				)
			)
		)
		(property "Value" ""
			(at 0 0 180)
			(layer "F.Fab")
			(effects
				(font
					(size 1.27 1.27)
				)
			)
		)
		(duplicate_pad_numbers_are_jumpers no)
		(fp_line
			(start 0.7874 0.4064)
			(end -0.7874 0.4064)
			(stroke
				(width 0.1524)
				(type default)
			)
			(layer "F.SilkS")
		)
		(fp_line
			(start 0.7874 -0.4064)
			(end 0.7874 0.4064)
			(stroke
				(width 0.1524)
				(type default)
			)
			(layer "F.SilkS")
		)
		(fp_line
			(start -0.7874 0.4064)
			(end -0.7874 -0.4064)
			(stroke
				(width 0.1524)
				(type default)
			)
			(layer "F.SilkS")
		)
		(fp_line
			(start -0.7874 -0.4064)
			(end 0.7874 -0.4064)
			(stroke
				(width 0.1524)
				(type default)
			)
			(layer "F.SilkS")
		)
		(fp_line
			(start 0.67945 0.3048)
			(end 0.120396 0.3048)
			(stroke
				(width 0.1)
				(type default)
			)
			(layer "F.Fab")
		)
		(fp_line
			(start 0.67945 -0.3048)
			(end 0.67945 0.3048)
			(stroke
				(width 0.1)
				(type default)
			)
			(layer "F.Fab")
		)
		(fp_line
			(start 0.12065 -0.2794)
			(end 0.12065 -0.3048)
			(stroke
				(width 0.1)
				(type default)
			)
			(layer "F.Fab")
		)
		(fp_line
			(start 0.12065 -0.3048)
			(end 0.67945 -0.3048)
			(stroke
				(width 0.1)
				(type default)
			)
			(layer "F.Fab")
		)
		(fp_line
			(start 0.120396 0.3048)
			(end 0.120396 0.2794)
			(stroke
				(width 0.1)
				(type default)
			)
			(layer "F.Fab")
		)
		(fp_line
			(start 0.120396 0.2794)
			(end -0.12065 0.2794)
			(stroke
				(width 0.1)
				(type default)
			)
			(layer "F.Fab")
		)
		(fp_line
			(start -0.12065 0.3048)
			(end -0.67945 0.3048)
			(stroke
				(width 0.1)
				(type default)
			)
			(layer "F.Fab")
		)
		(fp_line
			(start -0.12065 0.2794)
			(end -0.12065 0.3048)
			(stroke
				(width 0.1)
				(type default)
			)
			(layer "F.Fab")
		)
		(fp_line
			(start -0.12065 -0.2794)
			(end 0.12065 -0.2794)
			(stroke
				(width 0.1)
				(type default)
			)
			(layer "F.Fab")
		)
		(fp_line
			(start -0.12065 -0.305054)
			(end -0.12065 -0.2794)
			(stroke
				(width 0.1)
				(type default)
			)
			(layer "F.Fab")
		)
		(fp_line
			(start -0.67945 0.3048)
			(end -0.67945 -0.305054)
			(stroke
				(width 0.1)
				(type default)
			)
			(layer "F.Fab")
		)
		(fp_line
			(start -0.67945 -0.305054)
			(end -0.12065 -0.305054)
			(stroke
				(width 0.1)
				(type default)
			)
			(layer "F.Fab")
		)
		(pad "1" smd circle
			(at -0.40005 0 180)
			(size 0 0)
			(layers "F.Cu" "F.Mask" "F.Paste")
			(net "GPU_3V3IO_RSVD3")
		)
		(pad "2" smd circle
			(at 0.40005 0 180)
			(size 0 0)
			(layers "F.Cu" "F.Mask" "F.Paste")
			(net "GPU_3V3IO_RSVD3_ISO")
		)
	)
	(footprint ""
		(layer "F.Cu")
		(at 300.21022 -419.02761 -90)
		(property "Reference" "R4122"
			(at 0 0 270)
			(layer "F.SilkS")
			(hide yes)
			(effects
				(font
					(size 1.27 1.27)
				)
			)
		)
		(property "Value" ""
			(at 0 0 270)
			(layer "F.Fab")
			(effects
				(font
					(size 1.27 1.27)
				)
			)
		)
		(duplicate_pad_numbers_are_jumpers no)
		(fp_line
			(start -0.7874 0.4064)
			(end -0.7874 -0.4064)
			(stroke
				(width 0.1524)
				(type default)
			)
			(layer "F.SilkS")
		)
		(fp_line
			(start 0.7874 0.4064)
			(end -0.7874 0.4064)
			(stroke
				(width 0.1524)
				(type default)
			)
			(layer "F.SilkS")
		)
		(fp_line
			(start -0.7874 -0.4064)
			(end 0.7874 -0.4064)
			(stroke
				(width 0.1524)
				(type default)
			)
			(layer "F.SilkS")
		)
		(fp_line
			(start 0.7874 -0.4064)
			(end 0.7874 0.4064)
			(stroke
				(width 0.1524)
				(type default)
			)
			(layer "F.SilkS")
		)
		(fp_line
			(start -0.67945 0.3048)
			(end -0.67945 -0.305054)
			(stroke
				(width 0.1)
				(type default)
			)
			(layer "F.Fab")
		)
		(fp_line
			(start -0.12065 0.3048)
			(end -0.67945 0.3048)
			(stroke
				(width 0.1)
				(type default)
			)
			(layer "F.Fab")
		)
		(fp_line
			(start 0.120396 0.3048)
			(end 0.120396 0.2794)
			(stroke
				(width 0.1)
				(type default)
			)
			(layer "F.Fab")
		)
		(fp_line
			(start 0.67945 0.3048)
			(end 0.120396 0.3048)
			(stroke
				(width 0.1)
				(type default)
			)
			(layer "F.Fab")
		)
		(fp_line
			(start -0.12065 0.2794)
			(end -0.12065 0.3048)
			(stroke
				(width 0.1)
				(type default)
			)
			(layer "F.Fab")
		)
		(fp_line
			(start 0.120396 0.2794)
			(end -0.12065 0.2794)
			(stroke
				(width 0.1)
				(type default)
			)
			(layer "F.Fab")
		)
		(fp_line
			(start -0.12065 -0.2794)
			(end 0.12065 -0.2794)
			(stroke
				(width 0.1)
				(type default)
			)
			(layer "F.Fab")
		)
		(fp_line
			(start 0.12065 -0.2794)
			(end 0.12065 -0.3048)
			(stroke
				(width 0.1)
				(type default)
			)
			(layer "F.Fab")
		)
		(fp_line
			(start 0.12065 -0.3048)
			(end 0.67945 -0.3048)
			(stroke
				(width 0.1)
				(type default)
			)
			(layer "F.Fab")
		)
		(fp_line
			(start 0.67945 -0.3048)
			(end 0.67945 0.3048)
			(stroke
				(width 0.1)
				(type default)
			)
			(layer "F.Fab")
		)
		(fp_line
			(start -0.67945 -0.305054)
			(end -0.12065 -0.305054)
			(stroke
				(width 0.1)
				(type default)
			)
			(layer "F.Fab")
		)
		(fp_line
			(start -0.12065 -0.305054)
			(end -0.12065 -0.2794)
			(stroke
				(width 0.1)
				(type default)
			)
			(layer "F.Fab")
		)
		(pad "1" smd circle
			(at -0.40005 0 270)
			(size 0 0)
			(layers "F.Cu" "F.Mask" "F.Paste")
			(net "PRSNT_CABLE_GPU_B3_N")
		)
		(pad "2" smd circle
			(at 0.40005 0 270)
			(size 0 0)
			(layers "F.Cu" "F.Mask" "F.Paste")
			(net "GND")
		)
	)
	(footprint ""
		(layer "F.Cu")
		(at 407.91257 -157.691328)
		(property "Reference" "PC641"
			(at 0 0 0)
			(layer "F.SilkS")
			(hide yes)
			(effects
				(font
					(size 1.27 1.27)
				)
			)
		)
		(property "Value" ""
			(at 0 0 0)
			(layer "F.Fab")
			(effects
				(font
					(size 1.27 1.27)
				)
			)
		)
		(duplicate_pad_numbers_are_jumpers no)
		(fp_line
			(start -1.524 -0.762)
			(end 1.524 -0.762)
			(stroke
				(width 0.1524)
				(type default)
			)
			(layer "F.SilkS")
		)
		(fp_line
			(start -1.524 0.762)
			(end -1.524 -0.762)
			(stroke
				(width 0.1524)
				(type default)
			)
			(layer "F.SilkS")
		)
		(fp_line
			(start 1.524 -0.762)
			(end 1.524 0.762)
			(stroke
				(width 0.1524)
				(type default)
			)
			(layer "F.SilkS")
		)
		(fp_line
			(start 1.524 0.762)
			(end -1.524 0.762)
			(stroke
				(width 0.1524)
				(type default)
			)
			(layer "F.SilkS")
		)
		(fp_line
			(start -1.1049 -0.724916)
			(end -1.1049 0.724916)
			(stroke
				(width 0.1)
				(type default)
			)
			(layer "F.Fab")
		)
		(fp_line
			(start -1.1049 0.724916)
			(end 1.1049 0.724916)
			(stroke
				(width 0.1)
				(type default)
			)
			(layer "F.Fab")
		)
		(fp_line
			(start 1.1049 -0.724916)
			(end -1.1049 -0.724916)
			(stroke
				(width 0.1)
				(type default)
			)
			(layer "F.Fab")
		)
		(fp_line
			(start 1.1049 0.724916)
			(end 1.1049 -0.724916)
			(stroke
				(width 0.1)
				(type default)
			)
			(layer "F.Fab")
		)
		(pad "1" smd rect
			(at -0.889 0 180)
			(size 1.016 1.27)
			(layers "F.Cu" "F.Mask" "F.Paste")
			(net "PVCCD_HV_CPU0")
		)
		(pad "2" smd rect
			(at 0.889 0 180)
			(size 1.016 1.27)
			(layers "F.Cu" "F.Mask" "F.Paste")
			(net "GND")
		)
	)
)
